(kicad_pcb
	(version 20260206)
	(generator "pcbnew")
	(generator_version "10.0")
	(general
		(thickness 1.6)
		(legacy_teardrops no)
	)
	(paper "A4")
	(title_block
		(title "baseboard — 13948-1b.1110WZS1818.brd")
		(comment 1 "Honey Badger (Wiwynn) / footprints 1978-1986 of 2523")
	)
	(layers
		(0 "F.Cu" signal "TOP")
		(4 "In1.Cu" signal "L2GND")
		(6 "In2.Cu" signal "L3")
		(8 "In3.Cu" signal "L4VCC")
		(10 "In4.Cu" signal "L5VCC")
		(12 "In5.Cu" signal "L6")
		(14 "In6.Cu" signal "L7GND")
		(2 "B.Cu" signal "BOTTOM")
		(9 "F.Adhes" user "F.Adhesive")
		(11 "B.Adhes" user "B.Adhesive")
		(13 "F.Paste" user "Package Geometry/Pastemask Top")
		(15 "B.Paste" user "Package Geometry/Pastemask Bottom")
		(5 "F.SilkS" user "Ref Des/Silkscreen Top")
		(7 "B.SilkS" user "Ref Des/Silkscreen Bottom")
		(1 "F.Mask" user "Board Geometry/Soldermask Top")
		(3 "B.Mask" user "Board Geometry/Soldermask Bottom")
		(17 "Dwgs.User" user "User.Drawings")
		(19 "Cmts.User" user "User.Comments")
		(21 "Eco1.User" user "User.Eco1")
		(23 "Eco2.User" user "User.Eco2")
		(25 "Edge.Cuts" user "Board Geometry/Outline")
		(27 "Margin" user)
		(31 "F.CrtYd" user "Package Geometry/Place Bound Top")
		(29 "B.CrtYd" user "Package Geometry/Place Bound Bottom")
		(35 "F.Fab" user "Ref Des/Assembly Top")
		(33 "B.Fab" user "Ref Des/Assembly Bottom")
	)
	(footprint ""
		(layer "B.Cu")
		(at 120.015 -36.703 -90)
		(property "Reference" "SR624"
			(at 0 0 90)
			(layer "B.SilkS")
			(hide yes)
			(effects
				(font
					(size 1.27 1.27)
				)
				(justify mirror)
			)
		)
		(property "Value" "2K2R2F-GP"
			(at -0.064008 -3.993896 270)
			(unlocked yes)
			(layer "B.Fab")
			(hide yes)
			(effects
				(font
					(size 1.016 1.016)
					(thickness 0.1524)
				)
				(justify mirror)
			)
		)
		(property "Device Type" "R402H16"
			(at -0.064008 -5.517896 270)
			(unlocked yes)
			(layer "B.Fab")
			(hide yes)
			(effects
				(font
					(size 1.016 1.016)
					(thickness 0.1524)
				)
				(justify mirror)
			)
		)
		(duplicate_pad_numbers_are_jumpers no)
		(fp_line
			(start -0.508 -0.9398)
			(end 0.508 -0.9398)
			(stroke
				(width 0.1524)
				(type default)
			)
			(layer "B.SilkS")
		)
		(fp_line
			(start 0.508 -0.9398)
			(end 0.508 0.9398)
			(stroke
				(width 0.1524)
				(type default)
			)
			(layer "B.SilkS")
		)
		(fp_rect
			(start 0.508 0.9398)
			(end -0.508 -0.9398)
			(stroke
				(width 0)
				(type default)
			)
			(fill no)
			(layer "B.CrtYd")
		)
		(fp_rect
			(start 0.508 0.9398)
			(end -0.508 -0.9398)
			(stroke
				(width 0)
				(type default)
			)
			(fill no)
			(layer "B.Fab")
		)
		(pad "1" smd custom
			(at 0 -0.4445 90)
			(size 0.1397 0.1397)
			(layers "B.Cu" "B.Mask" "B.Paste")
			(net "P1V8_C")
			(options
				(clearance outline)
				(anchor circle)
			)
			(primitives
				(gr_poly
					(pts
						(arc
							(start -0.1778 0.2794)
							(mid -0.249642 0.249642)
							(end -0.2794 0.1778)
						)
						(arc
							(start -0.2794 -0.1778)
							(mid -0.249642 -0.249642)
							(end -0.1778 -0.2794)
						)
						(arc
							(start 0.1778 -0.2794)
							(mid 0.249642 -0.249642)
							(end 0.2794 -0.1778)
						)
						(arc
							(start 0.2794 0.1778)
							(mid 0.249642 0.249642)
							(end 0.1778 0.2794)
						)
					)
					(width 0)
					(fill yes)
				)
			)
		)
		(pad "2" smd custom
			(at 0 0.4445 90)
			(size 0.1397 0.1397)
			(layers "B.Cu" "B.Mask" "B.Paste")
			(net "IOC_SCL_4")
			(options
				(clearance outline)
				(anchor circle)
			)
			(primitives
				(gr_poly
					(pts
						(arc
							(start -0.1778 0.2794)
							(mid -0.249642 0.249642)
							(end -0.2794 0.1778)
						)
						(arc
							(start -0.2794 -0.1778)
							(mid -0.249642 -0.249642)
							(end -0.1778 -0.2794)
						)
						(arc
							(start 0.1778 -0.2794)
							(mid 0.249642 -0.249642)
							(end 0.2794 -0.1778)
						)
						(arc
							(start 0.2794 0.1778)
							(mid 0.249642 0.249642)
							(end 0.1778 0.2794)
						)
					)
					(width 0)
					(fill yes)
				)
			)
		)
	)
	(footprint ""
		(layer "B.Cu")
		(at 299.212 -178.1302 -90)
		(property "Reference" "C208"
			(at 0 0 90)
			(layer "B.SilkS")
			(hide yes)
			(effects
				(font
					(size 1.27 1.27)
				)
				(justify mirror)
			)
		)
		(property "Value" "SC1U10V2KX-1GP"
			(at -1.1811 -2.7051 270)
			(unlocked yes)
			(layer "B.Fab")
			(hide yes)
			(effects
				(font
					(size 1.016 1.016)
					(thickness 0.1524)
				)
				(justify mirror)
			)
		)
		(property "Device Type" "C402H22"
			(at -1.1811 -4.2291 270)
			(unlocked yes)
			(layer "B.Fab")
			(hide yes)
			(effects
				(font
					(size 1.016 1.016)
					(thickness 0.1524)
				)
				(justify mirror)
			)
		)
		(duplicate_pad_numbers_are_jumpers no)
		(fp_rect
			(start 0.4318 0.9525)
			(end -0.4318 -0.9525)
			(stroke
				(width 0)
				(type default)
			)
			(fill no)
			(layer "B.CrtYd")
		)
		(fp_rect
			(start 0.4318 0.9525)
			(end -0.4318 -0.9525)
			(stroke
				(width 0)
				(type default)
			)
			(fill no)
			(layer "B.Fab")
		)
		(pad "1" smd custom
			(at 0 -0.4445 90)
			(size 0.1524 0.1524)
			(layers "B.Cu" "B.Mask" "B.Paste")
			(net "P3V3_STBY")
			(options
				(clearance outline)
				(anchor circle)
			)
			(primitives
				(gr_poly
					(pts
						(arc
							(start 0.3048 0.2032)
							(mid 0.275042 0.275042)
							(end 0.2032 0.3048)
						)
						(arc
							(start -0.2032 0.3048)
							(mid -0.275042 0.275042)
							(end -0.3048 0.2032)
						)
						(arc
							(start -0.3048 -0.2032)
							(mid -0.275042 -0.275042)
							(end -0.2032 -0.3048)
						)
						(arc
							(start 0.2032 -0.3048)
							(mid 0.275042 -0.275042)
							(end 0.3048 -0.2032)
						)
					)
					(width 0)
					(fill yes)
				)
			)
		)
		(pad "2" smd custom
			(at 0 0.4445 90)
			(size 0.1524 0.1524)
			(layers "B.Cu" "B.Mask" "B.Paste")
			(net "GND")
			(options
				(clearance outline)
				(anchor circle)
			)
			(primitives
				(gr_poly
					(pts
						(arc
							(start 0.3048 0.2032)
							(mid 0.275042 0.275042)
							(end 0.2032 0.3048)
						)
						(arc
							(start -0.2032 0.3048)
							(mid -0.275042 0.275042)
							(end -0.3048 0.2032)
						)
						(arc
							(start -0.3048 -0.2032)
							(mid -0.275042 -0.275042)
							(end -0.2032 -0.3048)
						)
						(arc
							(start 0.2032 -0.3048)
							(mid 0.275042 -0.275042)
							(end 0.3048 -0.2032)
						)
					)
					(width 0)
					(fill yes)
				)
			)
		)
	)
	(footprint ""
		(layer "B.Cu")
		(at 109.23016 -32.639)
		(property "Reference" "STP46"
			(at 0 0 0)
			(layer "B.SilkS")
			(hide yes)
			(effects
				(font
					(size 1.27 1.27)
				)
				(justify mirror)
			)
		)
		(property "Value" "TPAD28"
			(at -0.0127 -1.8034 0)
			(unlocked yes)
			(layer "B.Fab")
			(hide yes)
			(effects
				(font
					(size 1.016 1.016)
					(thickness 0.1524)
				)
				(justify mirror)
			)
		)
		(property "Device Type" "TPAD28"
			(at -0.0127 -3.3274 0)
			(unlocked yes)
			(layer "B.Fab")
			(hide yes)
			(effects
				(font
					(size 1.016 1.016)
					(thickness 0.1524)
				)
				(justify mirror)
			)
		)
		(duplicate_pad_numbers_are_jumpers no)
		(fp_poly
			(pts
				(arc
					(start 0.3556 0)
					(mid -0.3556 0)
					(end 0.3556 0)
				)
			)
			(stroke
				(width 0)
				(type default)
			)
			(fill no)
			(layer "B.CrtYd")
		)
		(fp_poly
			(pts
				(arc
					(start 0.6096 0)
					(mid -0.6096 0)
					(end 0.6096 0)
				)
			)
			(stroke
				(width 0)
				(type default)
			)
			(fill no)
			(layer "B.Fab")
		)
		(pad "1" smd circle
			(at 0 0 180)
			(size 0.7112 0.7112)
			(layers "B.Cu" "B.Mask" "B.Paste")
			(net "IOC_GPIO_6")
		)
	)
	(footprint ""
		(layer "B.Cu")
		(at 324.358 -182.372)
		(property "Reference" "R5762"
			(at 0 0 0)
			(layer "B.SilkS")
			(hide yes)
			(effects
				(font
					(size 1.27 1.27)
				)
				(justify mirror)
			)
		)
		(property "Value" "1KR2F-3-GP"
			(at -0.064008 -3.993896 0)
			(unlocked yes)
			(layer "B.Fab")
			(hide yes)
			(effects
				(font
					(size 1.016 1.016)
					(thickness 0.1524)
				)
				(justify mirror)
			)
		)
		(property "Device Type" "R402H16"
			(at -0.064008 -5.517896 0)
			(unlocked yes)
			(layer "B.Fab")
			(hide yes)
			(effects
				(font
					(size 1.016 1.016)
					(thickness 0.1524)
				)
				(justify mirror)
			)
		)
		(duplicate_pad_numbers_are_jumpers no)
		(fp_line
			(start -0.508 -0.9398)
			(end 0.508 -0.9398)
			(stroke
				(width 0.1524)
				(type default)
			)
			(layer "B.SilkS")
		)
		(fp_line
			(start 0.508 -0.9398)
			(end 0.508 0.9398)
			(stroke
				(width 0.1524)
				(type default)
			)
			(layer "B.SilkS")
		)
		(fp_rect
			(start 0.508 0.9398)
			(end -0.508 -0.9398)
			(stroke
				(width 0)
				(type default)
			)
			(fill no)
			(layer "B.CrtYd")
		)
		(fp_rect
			(start 0.508 0.9398)
			(end -0.508 -0.9398)
			(stroke
				(width 0)
				(type default)
			)
			(fill no)
			(layer "B.Fab")
		)
		(pad "1" smd custom
			(at 0 -0.4445 180)
			(size 0.1397 0.1397)
			(layers "B.Cu" "B.Mask" "B.Paste")
			(net "ADC_P0V955_C")
			(options
				(clearance outline)
				(anchor circle)
			)
			(primitives
				(gr_poly
					(pts
						(arc
							(start -0.1778 0.2794)
							(mid -0.249642 0.249642)
							(end -0.2794 0.1778)
						)
						(arc
							(start -0.2794 -0.1778)
							(mid -0.249642 -0.249642)
							(end -0.1778 -0.2794)
						)
						(arc
							(start 0.1778 -0.2794)
							(mid 0.249642 -0.249642)
							(end 0.2794 -0.1778)
						)
						(arc
							(start 0.2794 0.1778)
							(mid 0.249642 0.249642)
							(end 0.1778 0.2794)
						)
					)
					(width 0)
					(fill yes)
				)
			)
		)
		(pad "2" smd custom
			(at 0 0.4445 180)
			(size 0.1397 0.1397)
			(layers "B.Cu" "B.Mask" "B.Paste")
			(net "GND")
			(options
				(clearance outline)
				(anchor circle)
			)
			(primitives
				(gr_poly
					(pts
						(arc
							(start -0.1778 0.2794)
							(mid -0.249642 0.249642)
							(end -0.2794 0.1778)
						)
						(arc
							(start -0.2794 -0.1778)
							(mid -0.249642 -0.249642)
							(end -0.1778 -0.2794)
						)
						(arc
							(start 0.1778 -0.2794)
							(mid 0.249642 -0.249642)
							(end 0.2794 -0.1778)
						)
						(arc
							(start 0.2794 0.1778)
							(mid 0.249642 0.249642)
							(end 0.1778 0.2794)
						)
					)
					(width 0)
					(fill yes)
				)
			)
		)
	)
	(footprint ""
		(layer "B.Cu")
		(at 100.21697 -108.204)
		(property "Reference" "TP264"
			(at 0 0 0)
			(layer "B.SilkS")
			(hide yes)
			(effects
				(font
					(size 1.27 1.27)
				)
				(justify mirror)
			)
		)
		(property "Value" "TPAD28"
			(at -0.0127 -1.8034 0)
			(unlocked yes)
			(layer "B.Fab")
			(hide yes)
			(effects
				(font
					(size 1.016 1.016)
					(thickness 0.1524)
				)
				(justify mirror)
			)
		)
		(property "Device Type" "TPAD28"
			(at -0.0127 -3.3274 0)
			(unlocked yes)
			(layer "B.Fab")
			(hide yes)
			(effects
				(font
					(size 1.016 1.016)
					(thickness 0.1524)
				)
				(justify mirror)
			)
		)
		(duplicate_pad_numbers_are_jumpers no)
		(fp_poly
			(pts
				(arc
					(start 0.3556 0)
					(mid -0.3556 0)
					(end 0.3556 0)
				)
			)
			(stroke
				(width 0)
				(type default)
			)
			(fill no)
			(layer "B.CrtYd")
		)
		(fp_poly
			(pts
				(arc
					(start 0.6096 0)
					(mid -0.6096 0)
					(end 0.6096 0)
				)
			)
			(stroke
				(width 0)
				(type default)
			)
			(fill no)
			(layer "B.Fab")
		)
		(pad "1" smd circle
			(at 0 0 180)
			(size 0.7112 0.7112)
			(layers "B.Cu" "B.Mask" "B.Paste")
			(net "SIO_D_OUT")
		)
	)
	(footprint ""
		(layer "B.Cu")
		(at 162.814 -120.396)
		(property "Reference" "SR858"
			(at 0 0 0)
			(layer "B.SilkS")
			(hide yes)
			(effects
				(font
					(size 1.27 1.27)
				)
				(justify mirror)
			)
		)
		(property "Value" "0R2J-2-GP"
			(at -0.064008 -3.993896 0)
			(unlocked yes)
			(layer "B.Fab")
			(hide yes)
			(effects
				(font
					(size 1.016 1.016)
					(thickness 0.1524)
				)
				(justify mirror)
			)
		)
		(property "Device Type" "R402H16"
			(at -0.064008 -5.517896 0)
			(unlocked yes)
			(layer "B.Fab")
			(hide yes)
			(effects
				(font
					(size 1.016 1.016)
					(thickness 0.1524)
				)
				(justify mirror)
			)
		)
		(duplicate_pad_numbers_are_jumpers no)
		(fp_line
			(start -0.508 -0.9398)
			(end 0.508 -0.9398)
			(stroke
				(width 0.1524)
				(type default)
			)
			(layer "B.SilkS")
		)
		(fp_line
			(start 0.508 -0.9398)
			(end 0.508 0.9398)
			(stroke
				(width 0.1524)
				(type default)
			)
			(layer "B.SilkS")
		)
		(fp_rect
			(start 0.508 0.9398)
			(end -0.508 -0.9398)
			(stroke
				(width 0)
				(type default)
			)
			(fill no)
			(layer "B.CrtYd")
		)
		(fp_rect
			(start 0.508 0.9398)
			(end -0.508 -0.9398)
			(stroke
				(width 0)
				(type default)
			)
			(fill no)
			(layer "B.Fab")
		)
		(pad "1" smd custom
			(at 0 -0.4445 180)
			(size 0.1397 0.1397)
			(layers "B.Cu" "B.Mask" "B.Paste")
			(net "EXP_RESET_MR_N")
			(options
				(clearance outline)
				(anchor circle)
			)
			(primitives
				(gr_poly
					(pts
						(arc
							(start -0.1778 0.2794)
							(mid -0.249642 0.249642)
							(end -0.2794 0.1778)
						)
						(arc
							(start -0.2794 -0.1778)
							(mid -0.249642 -0.249642)
							(end -0.1778 -0.2794)
						)
						(arc
							(start 0.1778 -0.2794)
							(mid 0.249642 -0.249642)
							(end 0.2794 -0.1778)
						)
						(arc
							(start 0.2794 0.1778)
							(mid 0.249642 0.249642)
							(end 0.1778 0.2794)
						)
					)
					(width 0)
					(fill yes)
				)
			)
		)
		(pad "2" smd custom
			(at 0 0.4445 180)
			(size 0.1397 0.1397)
			(layers "B.Cu" "B.Mask" "B.Paste")
			(net "EXP_RST")
			(options
				(clearance outline)
				(anchor circle)
			)
			(primitives
				(gr_poly
					(pts
						(arc
							(start -0.1778 0.2794)
							(mid -0.249642 0.249642)
							(end -0.2794 0.1778)
						)
						(arc
							(start -0.2794 -0.1778)
							(mid -0.249642 -0.249642)
							(end -0.1778 -0.2794)
						)
						(arc
							(start 0.1778 -0.2794)
							(mid 0.249642 -0.249642)
							(end 0.2794 -0.1778)
						)
						(arc
							(start 0.2794 0.1778)
							(mid 0.249642 0.249642)
							(end 0.1778 0.2794)
						)
					)
					(width 0)
					(fill yes)
				)
			)
		)
	)
	(footprint ""
		(layer "B.Cu")
		(at 110.50397 -72.644 180)
		(property "Reference" "SR731"
			(at 0 0 0)
			(layer "B.SilkS")
			(hide yes)
			(effects
				(font
					(size 1.27 1.27)
				)
				(justify mirror)
			)
		)
		(property "Value" "150R2F-1-GP"
			(at -0.064008 -3.993896 180)
			(unlocked yes)
			(layer "B.Fab")
			(hide yes)
			(effects
				(font
					(size 1.016 1.016)
					(thickness 0.1524)
				)
				(justify mirror)
			)
		)
		(property "Device Type" "R402H16"
			(at -0.064008 -5.517896 180)
			(unlocked yes)
			(layer "B.Fab")
			(hide yes)
			(effects
				(font
					(size 1.016 1.016)
					(thickness 0.1524)
				)
				(justify mirror)
			)
		)
		(duplicate_pad_numbers_are_jumpers no)
		(fp_line
			(start 0.508 -0.9398)
			(end 0.508 0.9398)
			(stroke
				(width 0.1524)
				(type default)
			)
			(layer "B.SilkS")
		)
		(fp_line
			(start -0.508 -0.9398)
			(end 0.508 -0.9398)
			(stroke
				(width 0.1524)
				(type default)
			)
			(layer "B.SilkS")
		)
		(fp_rect
			(start 0.508 0.9398)
			(end -0.508 -0.9398)
			(stroke
				(width 0)
				(type default)
			)
			(fill no)
			(layer "B.CrtYd")
		)
		(fp_rect
			(start 0.508 0.9398)
			(end -0.508 -0.9398)
			(stroke
				(width 0)
				(type default)
			)
			(fill no)
			(layer "B.Fab")
		)
		(pad "1" smd custom
			(at 0 -0.4445)
			(size 0.1397 0.1397)
			(layers "B.Cu" "B.Mask" "B.Paste")
			(net "P3V3_STBY")
			(options
				(clearance outline)
				(anchor circle)
			)
			(primitives
				(gr_poly
					(pts
						(arc
							(start -0.1778 0.2794)
							(mid -0.249642 0.249642)
							(end -0.2794 0.1778)
						)
						(arc
							(start -0.2794 -0.1778)
							(mid -0.249642 -0.249642)
							(end -0.1778 -0.2794)
						)
						(arc
							(start 0.1778 -0.2794)
							(mid 0.249642 -0.249642)
							(end 0.2794 -0.1778)
						)
						(arc
							(start 0.2794 0.1778)
							(mid 0.249642 0.249642)
							(end 0.1778 0.2794)
						)
					)
					(width 0)
					(fill yes)
				)
			)
		)
		(pad "2" smd custom
			(at 0 0.4445)
			(size 0.1397 0.1397)
			(layers "B.Cu" "B.Mask" "B.Paste")
			(net "EXP_HW_LED_R")
			(options
				(clearance outline)
				(anchor circle)
			)
			(primitives
				(gr_poly
					(pts
						(arc
							(start -0.1778 0.2794)
							(mid -0.249642 0.249642)
							(end -0.2794 0.1778)
						)
						(arc
							(start -0.2794 -0.1778)
							(mid -0.249642 -0.249642)
							(end -0.1778 -0.2794)
						)
						(arc
							(start 0.1778 -0.2794)
							(mid 0.249642 -0.249642)
							(end 0.2794 -0.1778)
						)
						(arc
							(start 0.2794 0.1778)
							(mid 0.249642 0.249642)
							(end 0.1778 0.2794)
						)
					)
					(width 0)
					(fill yes)
				)
			)
		)
	)
	(footprint ""
		(layer "B.Cu")
		(at 110.725966 -45.0596 -90)
		(property "Reference" "SC990"
			(at 0 0 90)
			(layer "B.SilkS")
			(hide yes)
			(effects
				(font
					(size 1.27 1.27)
				)
				(justify mirror)
			)
		)
		(property "Value" "SCD1U16V2KX-3GP"
			(at -1.1811 -2.7051 270)
			(unlocked yes)
			(layer "B.Fab")
			(hide yes)
			(effects
				(font
					(size 1.016 1.016)
					(thickness 0.1524)
				)
				(justify mirror)
			)
		)
		(property "Device Type" "C402H22"
			(at -1.1811 -4.2291 270)
			(unlocked yes)
			(layer "B.Fab")
			(hide yes)
			(effects
				(font
					(size 1.016 1.016)
					(thickness 0.1524)
				)
				(justify mirror)
			)
		)
		(duplicate_pad_numbers_are_jumpers no)
		(fp_rect
			(start 0.4318 0.9525)
			(end -0.4318 -0.9525)
			(stroke
				(width 0)
				(type default)
			)
			(fill no)
			(layer "B.CrtYd")
		)
		(fp_rect
			(start 0.4318 0.9525)
			(end -0.4318 -0.9525)
			(stroke
				(width 0)
				(type default)
			)
			(fill no)
			(layer "B.Fab")
		)
		(pad "1" smd custom
			(at 0 -0.4445 90)
			(size 0.1524 0.1524)
			(layers "B.Cu" "B.Mask" "B.Paste")
			(net "P1V8_C")
			(options
				(clearance outline)
				(anchor circle)
			)
			(primitives
				(gr_poly
					(pts
						(arc
							(start 0.3048 0.2032)
							(mid 0.275042 0.275042)
							(end 0.2032 0.3048)
						)
						(arc
							(start -0.2032 0.3048)
							(mid -0.275042 0.275042)
							(end -0.3048 0.2032)
						)
						(arc
							(start -0.3048 -0.2032)
							(mid -0.275042 -0.275042)
							(end -0.2032 -0.3048)
						)
						(arc
							(start 0.2032 -0.3048)
							(mid 0.275042 -0.275042)
							(end 0.3048 -0.2032)
						)
					)
					(width 0)
					(fill yes)
				)
			)
		)
		(pad "2" smd custom
			(at 0 0.4445 90)
			(size 0.1524 0.1524)
			(layers "B.Cu" "B.Mask" "B.Paste")
			(net "GND")
			(options
				(clearance outline)
				(anchor circle)
			)
			(primitives
				(gr_poly
					(pts
						(arc
							(start 0.3048 0.2032)
							(mid 0.275042 0.275042)
							(end 0.2032 0.3048)
						)
						(arc
							(start -0.2032 0.3048)
							(mid -0.275042 0.275042)
							(end -0.3048 0.2032)
						)
						(arc
							(start -0.3048 -0.2032)
							(mid -0.275042 -0.275042)
							(end -0.2032 -0.3048)
						)
						(arc
							(start 0.2032 -0.3048)
							(mid 0.275042 -0.275042)
							(end 0.3048 -0.2032)
						)
					)
					(width 0)
					(fill yes)
				)
			)
		)
	)
	(footprint ""
		(layer "B.Cu")
		(at 287.782 -166.878)
		(property "Reference" "TP134"
			(at 0 0 0)
			(layer "B.SilkS")
			(hide yes)
			(effects
				(font
					(size 1.27 1.27)
				)
				(justify mirror)
			)
		)
		(property "Value" "TPAD28"
			(at -0.0127 -1.8034 0)
			(unlocked yes)
			(layer "B.Fab")
			(hide yes)
			(effects
				(font
					(size 1.016 1.016)
					(thickness 0.1524)
				)
				(justify mirror)
			)
		)
		(property "Device Type" "TPAD28"
			(at -0.0127 -3.3274 0)
			(unlocked yes)
			(layer "B.Fab")
			(hide yes)
			(effects
				(font
					(size 1.016 1.016)
					(thickness 0.1524)
				)
				(justify mirror)
			)
		)
		(duplicate_pad_numbers_are_jumpers no)
		(fp_poly
			(pts
				(arc
					(start 0.3556 0)
					(mid -0.3556 0)
					(end 0.3556 0)
				)
			)
			(stroke
				(width 0)
				(type default)
			)
			(fill no)
			(layer "B.CrtYd")
		)
		(fp_poly
			(pts
				(arc
					(start 0.6096 0)
					(mid -0.6096 0)
					(end 0.6096 0)
				)
			)
			(stroke
				(width 0)
				(type default)
			)
			(fill no)
			(layer "B.Fab")
		)
		(pad "1" smd circle
			(at 0 0 180)
			(size 0.7112 0.7112)
			(layers "B.Cu" "B.Mask" "B.Paste")
			(net "TP_BMC_GPIOF3")
		)
	)
)
